(kicad_pcb
	(version 20260206)
	(generator "pcbnew")
	(generator_version "10.0")
	(general
		(thickness 1.6)
		(legacy_teardrops no)
	)
	(paper "A4")
	(title_block
		(title "netronome-mezz — pcbd0082-001_rev01_jul9_a.brd")
		(comment 1 "Open CloudServer (Microsoft) / footprints 166-167 of 714")
	)
	(layers
		(0 "F.Cu" signal "TOP")
		(4 "In1.Cu" signal "02_GND")
		(6 "In2.Cu" signal "03_SIG")
		(8 "In3.Cu" signal "04_SIG")
		(10 "In4.Cu" signal "05_GND")
		(12 "In5.Cu" signal "06_PWR1")
		(14 "In6.Cu" signal "07_SIG")
		(16 "In7.Cu" signal "08_SIG")
		(18 "In8.Cu" signal "09_GND")
		(2 "B.Cu" signal "BOTTOM")
		(9 "F.Adhes" user "F.Adhesive")
		(11 "B.Adhes" user "B.Adhesive")
		(13 "F.Paste" user "Package Geometry/Pastemask Top")
		(15 "B.Paste" user "Package Geometry/Pastemask Bottom")
		(5 "F.SilkS" user "Ref Des/Silkscreen Top")
		(7 "B.SilkS" user "Ref Des/Silkscreen Bottom")
		(1 "F.Mask" user "Board Geometry/Soldermask Top")
		(3 "B.Mask" user "Board Geometry/Soldermask Bottom")
		(17 "Dwgs.User" user "User.Drawings")
		(19 "Cmts.User" user "User.Comments")
		(21 "Eco1.User" user "User.Eco1")
		(23 "Eco2.User" user "User.Eco2")
		(25 "Edge.Cuts" user "Board Geometry/Outline")
		(27 "Margin" user)
		(31 "F.CrtYd" user "Package Geometry/Place Bound Top")
		(29 "B.CrtYd" user "Package Geometry/Place Bound Bottom")
		(35 "F.Fab" user "Ref Des/Assembly Top")
		(33 "B.Fab" user "Ref Des/Assembly Bottom")
		(45 "User.4" user "COMPVAL_TYPE_BOTTOM")
	)
	(footprint ""
		(layer "F.Cu")
		(at 31.115 38.1)
		(property "Reference" "U10"
			(at 3.96367 2.667 90)
			(unlocked yes)
			(layer "F.SilkS")
			(effects
				(font
					(size 0.7874 0.5842)
					(thickness 0.127)
				)
				(justify left)
			)
		)
		(property "Value" "*"
			(at -0.2921 1.813154 0)
			(unlocked yes)
			(layer "F.Fab")
			(hide yes)
			(effects
				(font
					(size 0.7874 0.5842)
					(thickness 0.2032)
				)
				(justify left)
			)
		)
		(property "Device Type" "ICSO0124"
			(at -0.2921 1.813154 0)
			(unlocked yes)
			(layer "F.Fab")
			(hide yes)
			(effects
				(font
					(size 0.7874 0.5842)
					(thickness 0.2032)
				)
				(justify left)
			)
		)
		(duplicate_pad_numbers_are_jumpers no)
		(fp_line
			(start -3.302 -3.302)
			(end -3.302 -2.794)
			(stroke
				(width 0.1524)
				(type default)
			)
			(layer "F.SilkS")
		)
		(fp_line
			(start -3.302 -2.794)
			(end -2.794 -3.302)
			(stroke
				(width 0.1524)
				(type default)
			)
			(layer "F.SilkS")
		)
		(fp_line
			(start -3.302 -2.794)
			(end -2.794 -3.302)
			(stroke
				(width 0.1524)
				(type default)
			)
			(layer "F.SilkS")
		)
		(fp_line
			(start -2.794 -3.302)
			(end -3.302 -3.302)
			(stroke
				(width 0.1524)
				(type default)
			)
			(layer "F.SilkS")
		)
		(fp_line
			(start 3.302 2.794)
			(end 3.302 3.302)
			(stroke
				(width 0.1524)
				(type default)
			)
			(layer "F.SilkS")
		)
		(fp_line
			(start 3.302 3.302)
			(end 2.794 3.302)
			(stroke
				(width 0.1524)
				(type default)
			)
			(layer "F.SilkS")
		)
		(fp_arc
			(start -4.0894 -3.048)
			(mid -4.015005 -3.227605)
			(end -3.8354 -3.302)
			(stroke
				(width 0.1524)
				(type default)
			)
			(layer "F.SilkS")
		)
		(fp_arc
			(start -4.018788 -2.872257)
			(mid -4.071088 -2.953301)
			(end -4.0894 -3.048)
			(stroke
				(width 0.1524)
				(type default)
			)
			(layer "F.SilkS")
		)
		(fp_arc
			(start -3.8354 -3.302)
			(mid -3.655795 -3.227605)
			(end -3.5814 -3.048)
			(stroke
				(width 0.1524)
				(type default)
			)
			(layer "F.SilkS")
		)
		(fp_arc
			(start -3.5814 -3.048)
			(mid -3.596526 -2.961656)
			(end -3.640099 -2.885592)
			(stroke
				(width 0.1524)
				(type default)
			)
			(layer "F.SilkS")
		)
		(fp_circle
			(center -3.8354 -3.048)
			(end -3.5814 -3.048)
			(stroke
				(width 0.1524)
				(type default)
			)
			(fill no)
			(layer "F.SilkS")
		)
		(fp_poly
			(pts
				(xy -1.905 -0.8382) (xy -0.8382 -0.8382) (xy -0.8382 -1.905) (xy -1.905 -1.905)
			)
			(stroke
				(width 0)
				(type default)
			)
			(fill yes)
			(layer "F.Paste")
		)
		(fp_poly
			(pts
				(xy -1.905 0.5334) (xy -0.8382 0.5334) (xy -0.8382 -0.5334) (xy -1.905 -0.5334)
			)
			(stroke
				(width 0)
				(type default)
			)
			(fill yes)
			(layer "F.Paste")
		)
		(fp_poly
			(pts
				(xy -1.905 1.905) (xy -0.8382 1.905) (xy -0.8382 0.8382) (xy -1.905 0.8382)
			)
			(stroke
				(width 0)
				(type default)
			)
			(fill yes)
			(layer "F.Paste")
		)
		(fp_poly
			(pts
				(xy -0.5334 -0.8382) (xy 0.5334 -0.8382) (xy 0.5334 -1.905) (xy -0.5334 -1.905)
			)
			(stroke
				(width 0)
				(type default)
			)
			(fill yes)
			(layer "F.Paste")
		)
		(fp_poly
			(pts
				(xy -0.5334 0.5334) (xy 0.5334 0.5334) (xy 0.5334 -0.5334) (xy -0.5334 -0.5334)
			)
			(stroke
				(width 0)
				(type default)
			)
			(fill yes)
			(layer "F.Paste")
		)
		(fp_poly
			(pts
				(xy -0.5334 1.905) (xy 0.5334 1.905) (xy 0.5334 0.8382) (xy -0.5334 0.8382)
			)
			(stroke
				(width 0)
				(type default)
			)
			(fill yes)
			(layer "F.Paste")
		)
		(fp_poly
			(pts
				(xy 0.8382 -0.8382) (xy 1.905 -0.8382) (xy 1.905 -1.905) (xy 0.8382 -1.905)
			)
			(stroke
				(width 0)
				(type default)
			)
			(fill yes)
			(layer "F.Paste")
		)
		(fp_poly
			(pts
				(xy 0.8382 0.5334) (xy 1.905 0.5334) (xy 1.905 -0.5334) (xy 0.8382 -0.5334)
			)
			(stroke
				(width 0)
				(type default)
			)
			(fill yes)
			(layer "F.Paste")
		)
		(fp_poly
			(pts
				(xy 0.8382 1.905) (xy 1.905 1.905) (xy 1.905 0.8382) (xy 0.8382 0.8382)
			)
			(stroke
				(width 0)
				(type default)
			)
			(fill yes)
			(layer "F.Paste")
		)
		(fp_poly
			(pts
				(xy -3.937 2.54) (xy -3.937 -3.937) (xy 2.54 -3.937) (xy 3.937 -3.937) (xy 3.937 -2.54) (xy 3.937 3.937)
				(xy -2.54 3.937) (xy -3.937 3.937)
			)
			(stroke
				(width 0)
				(type default)
			)
			(fill no)
			(layer "F.CrtYd")
		)
		(fp_line
			(start -3.048 -3.048)
			(end -3.048 3.048)
			(stroke
				(width 0.1524)
				(type default)
			)
			(layer "F.Fab")
		)
		(fp_line
			(start -3.048 -2.413)
			(end -2.413 -3.048)
			(stroke
				(width 0.1524)
				(type default)
			)
			(layer "F.Fab")
		)
		(fp_line
			(start -3.048 3.048)
			(end 3.048 3.048)
			(stroke
				(width 0.1524)
				(type default)
			)
			(layer "F.Fab")
		)
		(fp_line
			(start 3.048 -3.048)
			(end -3.048 -3.048)
			(stroke
				(width 0.1524)
				(type default)
			)
			(layer "F.Fab")
		)
		(fp_line
			(start 3.048 3.048)
			(end 3.048 -3.048)
			(stroke
				(width 0.1524)
				(type default)
			)
			(layer "F.Fab")
		)
		(fp_circle
			(center -2.413 -2.286)
			(end -2.129003 -2.286)
			(stroke
				(width 0.1524)
				(type default)
			)
			(fill no)
			(layer "F.Fab")
		)
		(fp_text user "40"
			(at -2.667 -3.91033 0)
			(unlocked yes)
			(layer "F.SilkS")
			(effects
				(font
					(size 0.7874 0.5842)
					(thickness 0.127)
				)
				(justify left)
			)
		)
		(fp_text user "20"
			(at 2.286 3.83667 0)
			(unlocked yes)
			(layer "F.SilkS")
			(effects
				(font
					(size 0.7874 0.5842)
					(thickness 0.127)
				)
				(justify left)
			)
		)
		(pad "1" smd custom
			(at -2.9464 -2.250008 270)
			(size 0.06985 0.06985)
			(layers "F.Cu" "F.Mask" "F.Paste")
			(net "10N2412")
			(options
				(clearance outline)
				(anchor circle)
			)
			(primitives
				(gr_poly
					(pts
						(xy -0.1397 0.4064) (xy -0.1397 -0.3302) (xy -0.0635 -0.4064) (xy 0.1397 -0.4064) (xy 0.1397 0.4064)
					)
					(width 0)
					(fill yes)
				)
			)
		)
		(pad "2" smd rect
			(at -2.9464 -1.750009 270)
			(size 0.2794 0.8128)
			(layers "F.Cu" "F.Mask" "F.Paste")
			(net "CORE_FB_ALERT_L")
		)
		(pad "3" smd rect
			(at -2.9464 -1.25001 270)
			(size 0.2794 0.8128)
			(layers "F.Cu" "F.Mask" "F.Paste")
			(net "CORE_FB_FAULT_L")
		)
		(pad "4" smd rect
			(at -2.9464 -0.750011 270)
			(size 0.2794 0.8128)
			(layers "F.Cu" "F.Mask" "F.Paste")
			(net "PSU_I2C_SDA")
		)
		(pad "5" smd rect
			(at -2.9464 -0.250012 270)
			(size 0.2794 0.8128)
			(layers "F.Cu" "F.Mask" "F.Paste")
			(net "PSU_I2C_SCL")
		)
		(pad "6" smd rect
			(at -2.9464 0.250012 270)
			(size 0.2794 0.8128)
			(layers "F.Cu" "F.Mask" "F.Paste")
			(net "VDD_CORE_EN")
		)
		(pad "7" smd rect
			(at -2.9464 0.750011 270)
			(size 0.2794 0.8128)
			(layers "F.Cu" "F.Mask" "F.Paste")
			(net "GND")
		)
		(pad "8" smd rect
			(at -2.9464 1.25001 270)
			(size 0.2794 0.8128)
			(layers "F.Cu" "F.Mask" "F.Paste")
			(net "NFP_VDD_CORE_IMON")
		)
		(pad "9" smd rect
			(at -2.9464 1.750009 270)
			(size 0.2794 0.8128)
			(layers "F.Cu" "F.Mask" "F.Paste")
			(net "10N2411")
		)
		(pad "10" smd custom
			(at -2.9464 2.250008 270)
			(size 0.06985 0.06985)
			(layers "F.Cu" "F.Mask" "F.Paste")
			(net "10N2399")
			(options
				(clearance outline)
				(anchor circle)
			)
			(primitives
				(gr_poly
					(pts
						(xy 0.1397 0.4064) (xy 0.1397 -0.3302) (xy 0.0635 -0.4064) (xy -0.1397 -0.4064) (xy -0.1397 0.4064)
					)
					(width 0)
					(fill yes)
				)
			)
		)
		(pad "11" smd custom
			(at -2.250008 2.9464)
			(size 0.06985 0.06985)
			(layers "F.Cu" "F.Mask" "F.Paste")
			(net "10N2397")
			(options
				(clearance outline)
				(anchor circle)
			)
			(primitives
				(gr_poly
					(pts
						(xy -0.1397 0.4064) (xy -0.1397 -0.3302) (xy -0.0635 -0.4064) (xy 0.1397 -0.4064) (xy 0.1397 0.4064)
					)
					(width 0)
					(fill yes)
				)
			)
		)
		(pad "12" smd rect
			(at -1.750009 2.9464)
			(size 0.2794 0.8128)
			(layers "F.Cu" "F.Mask" "F.Paste")
			(net "10N2498")
		)
		(pad "13" smd rect
			(at -1.25001 2.9464)
			(size 0.2794 0.8128)
			(layers "F.Cu" "F.Mask" "F.Paste")
			(net "NFP_VDD_CORE_SENSE_VSS")
		)
		(pad "14" smd rect
			(at -0.750011 2.9464)
			(size 0.2794 0.8128)
			(layers "F.Cu" "F.Mask" "F.Paste")
			(net "10N2384")
		)
		(pad "15" smd rect
			(at -0.250012 2.9464)
			(size 0.2794 0.8128)
			(layers "F.Cu" "F.Mask" "F.Paste")
			(net "10N2504")
		)
		(pad "16" smd rect
			(at 0.250012 2.9464)
			(size 0.2794 0.8128)
			(layers "F.Cu" "F.Mask" "F.Paste")
			(net "10N2535")
		)
		(pad "17" smd rect
			(at 0.750011 2.9464)
			(size 0.2794 0.8128)
			(layers "F.Cu" "F.Mask" "F.Paste")
			(net "10N2528")
		)
		(pad "18" smd rect
			(at 1.25001 2.9464)
			(size 0.2794 0.8128)
			(layers "F.Cu" "F.Mask" "F.Paste")
			(net "NFP_VDD_CORE_TCOMPA")
		)
		(pad "19" smd rect
			(at 1.750009 2.9464)
			(size 0.2794 0.8128)
			(layers "F.Cu" "F.Mask" "F.Paste")
			(net "10N2381")
		)
		(pad "20" smd custom
			(at 2.250008 2.9464)
			(size 0.06985 0.06985)
			(layers "F.Cu" "F.Mask" "F.Paste")
			(net "VR_ODN_L")
			(options
				(clearance outline)
				(anchor circle)
			)
			(primitives
				(gr_poly
					(pts
						(xy 0.1397 0.4064) (xy 0.1397 -0.3302) (xy 0.0635 -0.4064) (xy -0.1397 -0.4064) (xy -0.1397 0.4064)
					)
					(width 0)
					(fill yes)
				)
			)
		)
		(pad "21" smd custom
			(at 2.9464 2.250008 90)
			(size 0.06985 0.06985)
			(layers "F.Cu" "F.Mask" "F.Paste")
			(net "VR_OD1_L")
			(options
				(clearance outline)
				(anchor circle)
			)
			(primitives
				(gr_poly
					(pts
						(xy -0.1397 0.4064) (xy -0.1397 -0.3302) (xy -0.0635 -0.4064) (xy 0.1397 -0.4064) (xy 0.1397 0.4064)
					)
					(width 0)
					(fill yes)
				)
			)
		)
		(pad "22" smd rect
			(at 2.9464 1.750009 90)
			(size 0.2794 0.8128)
			(layers "F.Cu" "F.Mask" "F.Paste")
			(net "_NC_NCP4200_SW4")
		)
		(pad "23" smd rect
			(at 2.9464 1.25001 90)
			(size 0.2794 0.8128)
			(layers "F.Cu" "F.Mask" "F.Paste")
			(net "_NC_NCP4200_SW3")
		)
		(pad "24" smd rect
			(at 2.9464 0.750011 90)
			(size 0.2794 0.8128)
			(layers "F.Cu" "F.Mask" "F.Paste")
			(net "_SW2")
		)
		(pad "25" smd rect
			(at 2.9464 0.250012 90)
			(size 0.2794 0.8128)
			(layers "F.Cu" "F.Mask" "F.Paste")
			(net "_SW1")
		)
		(pad "26" smd rect
			(at 2.9464 -0.250012 90)
			(size 0.2794 0.8128)
			(layers "F.Cu" "F.Mask" "F.Paste")
			(net "10N2403")
		)
		(pad "27" smd rect
			(at 2.9464 -0.750011 90)
			(size 0.2794 0.8128)
			(layers "F.Cu" "F.Mask" "F.Paste")
			(net "10N2409")
		)
		(pad "28" smd rect
			(at 2.9464 -1.25001 90)
			(size 0.2794 0.8128)
			(layers "F.Cu" "F.Mask" "F.Paste")
			(net "NFP_CORE_PWM2")
		)
		(pad "29" smd rect
			(at 2.9464 -1.750009 90)
			(size 0.2794 0.8128)
			(layers "F.Cu" "F.Mask" "F.Paste")
			(net "NFP_CORE_PWM1")
		)
		(pad "30" smd custom
			(at 2.9464 -2.250008 90)
			(size 0.06985 0.06985)
			(layers "F.Cu" "F.Mask" "F.Paste")
			(net "10N2370")
			(options
				(clearance outline)
				(anchor circle)
			)
			(primitives
				(gr_poly
					(pts
						(xy 0.1397 0.4064) (xy 0.1397 -0.3302) (xy 0.0635 -0.4064) (xy -0.1397 -0.4064) (xy -0.1397 0.4064)
					)
					(width 0)
					(fill yes)
				)
			)
		)
		(pad "31" smd custom
			(at 2.250008 -2.9464 180)
			(size 0.06985 0.06985)
			(layers "F.Cu" "F.Mask" "F.Paste")
			(net "_NFP_CORE_VID7")
			(options
				(clearance outline)
				(anchor circle)
			)
			(primitives
				(gr_poly
					(pts
						(xy -0.1397 0.4064) (xy -0.1397 -0.3302) (xy -0.0635 -0.4064) (xy 0.1397 -0.4064) (xy 0.1397 0.4064)
					)
					(width 0)
					(fill yes)
				)
			)
		)
		(pad "32" smd rect
			(at 1.750009 -2.9464 180)
			(size 0.2794 0.8128)
			(layers "F.Cu" "F.Mask" "F.Paste")
			(net "_NFP_CORE_VID6")
		)
		(pad "33" smd rect
			(at 1.25001 -2.9464 180)
			(size 0.2794 0.8128)
			(layers "F.Cu" "F.Mask" "F.Paste")
			(net "_NFP_CORE_VID5")
		)
		(pad "34" smd rect
			(at 0.750011 -2.9464 180)
			(size 0.2794 0.8128)
			(layers "F.Cu" "F.Mask" "F.Paste")
			(net "_NFP_CORE_VID4")
		)
		(pad "35" smd rect
			(at 0.250012 -2.9464 180)
			(size 0.2794 0.8128)
			(layers "F.Cu" "F.Mask" "F.Paste")
			(net "_NFP_CORE_VID3")
		)
		(pad "36" smd rect
			(at -0.250012 -2.9464 180)
			(size 0.2794 0.8128)
			(layers "F.Cu" "F.Mask" "F.Paste")
			(net "_NFP_CORE_VID2")
		)
		(pad "37" smd rect
			(at -0.750011 -2.9464 180)
			(size 0.2794 0.8128)
			(layers "F.Cu" "F.Mask" "F.Paste")
			(net "_NFP_CORE_VID1")
		)
		(pad "38" smd rect
			(at -1.25001 -2.9464 180)
			(size 0.2794 0.8128)
			(layers "F.Cu" "F.Mask" "F.Paste")
			(net "_NFP_CORE_VID0")
		)
		(pad "39" smd rect
			(at -1.750009 -2.9464 180)
			(size 0.2794 0.8128)
			(layers "F.Cu" "F.Mask" "F.Paste")
			(net "CPLD_CORE_PSI_L")
		)
		(pad "40" smd custom
			(at -2.250008 -2.9464 180)
			(size 0.06985 0.06985)
			(layers "F.Cu" "F.Mask" "F.Paste")
			(net "VDD_CORE_PGOOD")
			(options
				(clearance outline)
				(anchor circle)
			)
			(primitives
				(gr_poly
					(pts
						(xy 0.1397 0.4064) (xy 0.1397 -0.3302) (xy 0.0635 -0.4064) (xy -0.1397 -0.4064) (xy -0.1397 0.4064)
					)
					(width 0)
					(fill yes)
				)
			)
		)
		(pad "41" smd rect
			(at 0 0 90)
			(size 4.191 4.191)
			(layers "F.Cu" "F.Mask" "F.Paste")
			(net "GND")
		)
		(zone
			(layer "F.Cu")
			(hatch none 0.5)
			(connect_pads
				(clearance 0)
			)
			(min_thickness 0.25)
			(keepout
				(tracks allowed)
				(vias not_allowed)
				(pads allowed)
				(copperpour not_allowed)
				(footprints allowed)
			)
			(placement
				(enabled no)
				(sheetname "")
			)
			(fill
				(thermal_gap 0.5)
				(thermal_bridge_width 0.5)
				(island_removal_mode 0)
			)
			(polygon
				(pts
					(arc
						(start 27.6098 35.052)
						(mid 26.9494 35.052)
						(end 27.6098 35.052)
					)
				)
			)
		)
	)
	(footprint ""
		(layer "F.Cu")
		(at 20.955 29.337)
		(property "Reference" "R71"
			(at 0 0 0)
			(layer "F.SilkS")
			(hide yes)
			(effects
				(font
					(size 1.27 1.27)
				)
			)
		)
		(property "Value" "4.75K"
			(at -0.148158 1.3462 90)
			(unlocked yes)
			(layer "F.Fab")
			(hide yes)
			(effects
				(font
					(size 1.27 0.9652)
					(thickness 0.000001)
				)
				(justify left)
			)
		)
		(property "Device Type" "REST4024"
			(at -0.148158 1.3462 90)
			(unlocked yes)
			(layer "F.Fab")
			(hide yes)
			(effects
				(font
					(size 1.27 0.9652)
					(thickness 0.000001)
				)
				(justify left)
			)
		)
		(duplicate_pad_numbers_are_jumpers no)
		(fp_poly
			(pts
				(xy 0.635 1.0668) (xy 0.635 -1.0668) (xy -0.635 -1.0668) (xy -0.635 1.0668)
			)
			(stroke
				(width 0)
				(type default)
			)
			(fill no)
			(layer "F.CrtYd")
		)
		(fp_line
			(start -0.254 -0.508)
			(end 0.254 -0.508)
			(stroke
				(width 0.0254)
				(type default)
			)
			(layer "F.Fab")
		)
		(fp_line
			(start -0.254 0.508)
			(end -0.254 -0.508)
			(stroke
				(width 0.0254)
				(type default)
			)
			(layer "F.Fab")
		)
		(fp_line
			(start 0.254 -0.508)
			(end 0.254 0.508)
			(stroke
				(width 0.0254)
				(type default)
			)
			(layer "F.Fab")
		)
		(fp_line
			(start 0.254 0.508)
			(end -0.254 0.508)
			(stroke
				(width 0.0254)
				(type default)
			)
			(layer "F.Fab")
		)
		(pad "1" smd rect
			(at 0 -0.4191)
			(size 0.508 0.5334)
			(layers "F.Cu" "F.Mask" "F.Paste")
			(net "EXT_3.3V")
		)
		(pad "2" smd rect
			(at 0 0.4191)
			(size 0.508 0.5334)
			(layers "F.Cu" "F.Mask" "F.Paste")
			(net "DEBUG_CPLD_PGRM_JTAG_TDI")
		)
		(zone
			(layer "F.Cu")
			(hatch none 0.5)
			(connect_pads
				(clearance 0)
			)
			(min_thickness 0.25)
			(keepout
				(tracks not_allowed)
				(vias allowed)
				(pads allowed)
				(copperpour not_allowed)
				(footprints allowed)
			)
			(placement
				(enabled no)
				(sheetname "")
			)
			(fill
				(thermal_gap 0.5)
				(thermal_bridge_width 0.5)
				(island_removal_mode 0)
			)
			(polygon
				(pts
					(xy 20.9804 29.3116) (xy 20.9804 29.3624) (xy 20.9296 29.3624) (xy 20.9296 29.3116)
				)
			)
		)
	)
)
